# BARRELEYE_G2-BPX24-EVT-HW-EBOM-X00_20161124-add_2nd_source_X09-20161207-Final.xls — Summary (bom)
| PLATFORM SOURCING AND PSL COMPLIANCE |  |  |  |  |  |  |  |  |  |
| Platform Name: |  |  |  |  |  |  |  |  |  |
| REVISION HISTORY |  |  |  |  |  |  |  |  |  |
| BOM Revision: | ECR # | Revision Description | Originator | Date |  |  |  |  |  |
| Commodity Sourcing | # of components (X00 BOM) | % of Total | # of components (X01 BOM) | % of Total | # of components (X02 BOM) | % of Total | # of components (RTS) | % of Total | Risk Mitigation Plans in Place |
| Sole Source |  |  |  |  |  |  |  |  |  |
| Single Source |  |  |  |  |  |  |  |  |  |
| Multiple |  |  |  |  |  |  |  |  | NA |
| Total |  |  |  |  |  |  |  |  | NA |
|  |  | # of components | # of components aligned with Customer PSL* | % PSL alignment |  |  |  |  |  |
| Class 1 (Customer Managed) |  |  |  |  |  |  |  |  |  |
| Class 2 (ODM Managed to Customer PSL) |  |  |  |  |  |  |  |  |  |
| All other components(ODM Managed to ODM PSL) |  |  |  |  |  |  |  |  |  |
| *RFQ and/or Contract will list requirements for complying with Customer's PSL |  |  |  |  |  |  |  |  |  |
| Reference for quotation |  |  |  |  |  |  |  |  |  |
